FILE_TYPE = CONNECTIVITY;
{Allegro Design Entry HDL 17.4-2019 S026 (4007227) 1/17/2022}
"PAGE_NUMBER" = 420;
0"NC";
1"GND\g";
2"GND\g";
3"P1V8_CPU0_RT_1D\g";
4"GND\g";
5"RT_CPU0_P2_VQPS";
6"P1V8_CPU0_RT2_1A_1D\g";
7"P0V9_CPU0_RT2_2A_2D\g";
8"P0V9_CPU0_RT2_2A\g";
9"P1V8_CPU0_RT2_1A\g";
10"P0V9_CPU0_RT_2D\g";
11"GND\g";
12"GND\g";
13"NCF_CPU0_P2_GND";
14"NCF_A1_CPU0_P2_GND";
%"VCC_CORE"
"1","(-4700,4850)","0","pure_quanta_power","I10";
;
HDL_POWER"P0V9_CPU0_RT2_2A"
CDS_LIB"pure_quanta_power";
"A"8;
%"UNIVERSAL_GND"
"1","(-3150,1150)","0","pure_quanta_power","I11";
;
CDS_LIB"pure_quanta_power"
HDL_POWER"GND";
"A"12;
%"UNIVERSAL_GND"
"1","(-1475,775)","0","pure_quanta_power","I12";
;
CDS_LIB"pure_quanta_power"
HDL_POWER"GND";
"A"1;
%"Q_RES"
"2","(-1475,1075)","0","pure_quanta","I13";
;
LOCATION"R1083"
$SEC"1"
CDS_SEC"1"
TOLERANCE"5%"
MATERIAL"CHIP"
WATTAGE"1/20W"
VALUE"0"
PACK_TYPE"0201LF"
CDS_LIB"pure_quanta"
PART_NUMBER"CS00001JE10";
"A"
$PN"1"13;
"B"
$PN"2"1;
%"Q_RES"
"2","(-1325,1625)","0","pure_quanta","I14";
;
LOCATION"R1084"
$SEC"1"
CDS_SEC"1"
MATERIAL"CHIP"
TOLERANCE"5%"
PACK_TYPE"0201LF"
VALUE"0"
WATTAGE"1/20W"
CDS_LIB"pure_quanta"
PART_NUMBER"CS00001JE10";
"A"
$PN"1"14;
"B"
$PN"2"2;
%"UNIVERSAL_GND"
"1","(-1325,1325)","0","pure_quanta_power","I15";
;
CDS_LIB"pure_quanta_power"
HDL_POWER"GND";
"A"2;
%"UNIVERSAL_GND"
"1","(-1100,1875)","0","pure_quanta_power","I16";
;
CDS_LIB"pure_quanta_power"
HDL_POWER"GND";
"A"11;
%"PT5161LRS"
"5","(-2450,3400)","0","pure_quanta","I17";
;
LOCATION"U6012"
$SEC"5"
CDS_SEC"5"
MATERIAL"IC"
VALUE"PT5161LRS"
PART_TYPE"SMLF"
CDS_LIB"pure_quanta"
CDS_LMAN_SYM_OUTLINE"-350,2150,300,-2150"
NEEDS_NO_SIZE"TRUE"
PART_NUMBER"AJ051610U03";
"GND151"
$PN"V35"11;
"GND150"
$PN"V1"11;
"GND149"
$PN"U34"11;
"GND148"
$PN"U2"11;
"GND147"
$PN"T4"11;
"GND146"
$PN"T32"11;
"GND145"
$PN"T22"11;
"GND144"
$PN"T13"11;
"GND143"
$PN"L35"11;
"GND142"
$PN"L1"11;
"GND141"
$PN"K34"11;
"GND140"
$PN"K2"11;
"GND139"
$PN"J4"11;
"GND138"
$PN"J22"11;
"GND137"
$PN"H31"11;
"GND136"
$PN"H19"11;
"GND135"
$PN"H16"11;
"GND134"
$PN"H12"11;
"GND133"
$PN"FJ19"11;
"GND132"
$PN"FJ12"11;
"GND131"
$PN"FF21"11;
"GND130"
$PN"FF14"11;
"GND129"
$PN"FD35"11;
"GND128"
$PN"FD1"11;
"GND127"
$PN"FC9"11;
"GND126"
$PN"FC6"11;
"GND125"
$PN"FC3"11;
"GND124"
$PN"FC28"11;
"GND123"
$PN"FC25"11;
"GND122"
$PN"FC23"11;
"GND121"
$PN"FC19"11;
"GND120"
$PN"FB34"11;
"GND119"
$PN"FB2"11;
"GND118"
$PN"FA32"11;
"GND117"
$PN"FA15"11;
"GND116"
$PN"ET35"11;
"GND115"
$PN"ET1"11;
"GND114"
$PN"ER34"11;
"GND113"
$PN"ER2"11;
"GND112"
$PN"EP4"11;
"GND111"
$PN"EP32"11;
"GND110"
$PN"EP22"11;
"GND109"
$PN"EP13"11;
"GND108"
$PN"EJ35"11;
"GND107"
$PN"EJ1"11;
"GND106"
$PN"EH34"11;
"GND105"
$PN"EH2"11;
"GND104"
$PN"EG4"11;
"GND103"
$PN"EG32"11;
"GND102"
$PN"EG22"11;
"GND101"
$PN"EG13"11;
"GND100"
$PN"EB35"11;
"GND99"
$PN"EB1"11;
"GND98"
$PN"EA34"11;
"GND97"
$PN"EA2"11;
"GND96"
$PN"E33"11;
"GND95"
$PN"E27"11;
"GND94"
$PN"E14"11;
"GND93"
$PN"DY4"11;
"GND92"
$PN"DY32"11;
"GND91"
$PN"DY22"11;
"GND90"
$PN"DY13"11;
"GND89"
$PN"DR35"11;
"GND88"
$PN"DR1"11;
"GND87"
$PN"DP34"11;
"GND86"
$PN"DP2"11;
"GND85"
$PN"DN4"11;
"GND84"
$PN"DN32"11;
"GND83"
$PN"DN22"11;
"NCF_GND12"
$PN"FH34"13;
"NCF_GND11"
$PN"FH2"13;
"NCF_GND10"
$PN"FG35"13;
"NCF_GND9"
$PN"FG1"13;
"NCF_GND8"
$PN"FE34"13;
"NCF_GND7"
$PN"FE2"13;
"NCF_GND6"
$PN"D35"13;
"NCF_GND5"
$PN"D1"13;
"NCF_GND4"
$PN"C34"13;
"NCF_GND3"
$PN"C2"13;
"NCF_GND2"
$PN"A35"13;
"NCF_GND1"
$PN"A1"14;
"GND82"
$PN"DN13"12;
"GND81"
$PN"DH35"12;
"GND80"
$PN"DH1"12;
"GND79"
$PN"DG34"12;
"GND78"
$PN"DG2"12;
"GND77"
$PN"DF4"12;
"GND76"
$PN"DF32"12;
"GND75"
$PN"DF22"12;
"GND74"
$PN"DF13"12;
"GND73"
$PN"DA35"12;
"GND72"
$PN"DA1"12;
"GND71"
$PN"CY34"12;
"GND70"
$PN"CY2"12;
"GND69"
$PN"CW4"12;
"GND68"
$PN"CW32"12;
"GND67"
$PN"CW22"12;
"GND66"
$PN"CW13"12;
"GND65"
$PN"CP35"12;
"GND64"
$PN"CP1"12;
"GND63"
$PN"CN34"12;
"GND62"
$PN"CN2"12;
"GND61"
$PN"CM4"12;
"GND60"
$PN"CM32"12;
"GND59"
$PN"CM22"12;
"GND58"
$PN"CM13"12;
"GND57"
$PN"CG35"12;
"GND56"
$PN"CG1"12;
"GND55"
$PN"CF34"12;
"GND54"
$PN"CF2"12;
"GND53"
$PN"CE4"12;
"GND52"
$PN"CE32"12;
"GND51"
$PN"CE22"12;
"GND50"
$PN"CE13"12;
"GND49"
$PN"BY35"12;
"GND48"
$PN"BY1"12;
"GND47"
$PN"BW34"12;
"GND46"
$PN"BW2"12;
"GND45"
$PN"BV4"12;
"GND44"
$PN"BV32"12;
"GND43"
$PN"BV22"12;
"GND42"
$PN"BV13"12;
"GND41"
$PN"BN35"12;
"GND40"
$PN"BN1"12;
"GND39"
$PN"BM34"12;
"GND38"
$PN"BM2"12;
"GND37"
$PN"BL4"12;
"GND36"
$PN"BL32"12;
"GND35"
$PN"BL22"12;
"GND34"
$PN"BL13"12;
"GND33"
$PN"BF35"12;
"GND32"
$PN"BF1"12;
"GND31"
$PN"BE34"12;
"GND30"
$PN"BE2"12;
"GND29"
$PN"BD4"12;
"GND28"
$PN"BD32"12;
"GND27"
$PN"BD22"12;
"GND26"
$PN"BD13"12;
"GND25"
$PN"B19"12;
"GND24"
$PN"AW35"12;
"GND23"
$PN"AW1"12;
"GND22"
$PN"AV34"12;
"GND21"
$PN"AV2"12;
"GND20"
$PN"AU4"12;
"GND19"
$PN"AU32"12;
"GND18"
$PN"AU22"12;
"GND17"
$PN"AU13"12;
"GND16"
$PN"AM35"12;
"GND15"
$PN"AM1"12;
"GND14"
$PN"AL34"12;
"GND13"
$PN"AL2"12;
"GND12"
$PN"AK4"12;
"GND11"
$PN"AK32"12;
"GND10"
$PN"AK22"12;
"GND9"
$PN"AK13"12;
"GND8"
$PN"AE35"12;
"GND7"
$PN"AE1"12;
"GND6"
$PN"AD34"12;
"GND5"
$PN"AD2"12;
"GND4"
$PN"AC4"12;
"GND3"
$PN"AC32"12;
"GND2"
$PN"AC22"12;
"GND1"
$PN"AC13"12;
%"Q_RES"
"2","(-7675,3175)","0","pure_quanta","I18";
;
LOCATION"R1082"
$SEC"1"
CDS_SEC"1"
TOLERANCE"1%"
WATTAGE"1/20W"
PACK_TYPE"0201LF"
MATERIAL"CHIP"
VALUE"200"
CDS_LIB"pure_quanta"
PART_NUMBER"CS12001FE12";
"A"
$PN"1"5;
"B"
$PN"2"4;
%"Q_RES"
"2","(-8700,3725)","0","pure_quanta","I19";
;
LOCATION"R1081"
$SEC"1"
CDS_SEC"1"
WATTAGE"1/20W"
MATERIAL"EMPTY"
VALUE"1K"
TOLERANCE"1%"
PACK_TYPE"0201LF"
CDS_LIB"pure_quanta"
PART_NUMBER"CS21001FE07";
"A"
$PN"1"3;
"B"
$PN"2"5;
%"P1V0"
"1","(-8700,3950)","0","pure_quanta_power","I2";
;
HDL_POWER"P1V8_CPU0_RT_1D"
CDS_LIB"pure_quanta_power";
"A"3;
%"P1V0"
"1","(-8375,4225)","0","pure_quanta_power","I3";
;
HDL_POWER"P1V8_CPU0_RT2_1A_1D"
CDS_LIB"pure_quanta_power";
"A"6;
%"UNIVERSAL_GND"
"1","(-7675,2925)","0","pure_quanta_power","I4";
;
CDS_LIB"pure_quanta_power"
HDL_POWER"GND";
"A"4;
%"PT5161LRS"
"4","(-6525,3975)","0","pure_quanta","I6";
;
LOCATION"U6012"
$SEC"4"
CDS_SEC"4"
MATERIAL"IC"
PART_TYPE"SMLF"
VALUE"PT5161LRS"
CDS_LIB"pure_quanta"
CDS_LMAN_SYM_OUTLINE"-450,750,400,-750"
NEEDS_NO_SIZE"TRUE"
PART_NUMBER"AJ051610U03";
"PWR_2A_20"
$PN"T20"8;
"PWR_2A_19"
$PN"T17"8;
"PWR_2A_18"
$PN"EP20"8;
"PWR_2A_17"
$PN"EP17"8;
"PWR_2A_16"
$PN"EG20"8;
"PWR_2A_15"
$PN"EG17"8;
"PWR_2A_14"
$PN"DY20"8;
"PWR_2A_13"
$PN"DY17"8;
"PWR_2A_12"
$PN"DN20"8;
"PWR_2A_11"
$PN"DN17"8;
"PWR_2A_10"
$PN"DF20"7;
"PWR_2A_9"
$PN"DF17"7;
"PWR_2A_8"
$PN"BD20"7;
"PWR_2A_7"
$PN"BD17"7;
"PWR_2A_6"
$PN"AU20"8;
"PWR_2A_5"
$PN"AU17"8;
"PWR_2A_4"
$PN"AK20"8;
"PWR_2A_3"
$PN"AK17"8;
"PWR_2A_2"
$PN"AC20"8;
"PWR_2A_1"
$PN"AC17"8;
"PWR_1D"
$PN"BV17"6;
"PWR_2D_4"
$PN"CW20"10;
"PWR_2D_3"
$PN"CW17"10;
"PWR_2D_2"
$PN"BL20"10;
"PWR_2D_1"
$PN"BL17"10;
"PWR_1A_5"
$PN"CM20"9;
"PWR_1A_4"
$PN"CM17"9;
"PWR_1A_3"
$PN"CE20"9;
"PWR_1A_2"
$PN"CE17"9;
"PWR_1A_1"
$PN"BV20"9;
"VQPS"
$PN"G1"5;
%"P1V0"
"1","(-4675,3625)","0","pure_quanta_power","I7";
;
HDL_POWER"P0V9_CPU0_RT_2D"
CDS_LIB"pure_quanta_power";
"A"10;
%"P1V0"
"1","(-7800,4675)","0","pure_quanta_power","I8";
;
HDL_POWER"P1V8_CPU0_RT2_1A"
CDS_LIB"pure_quanta_power";
"A"9;
%"VCC_CORE"
"1","(-5275,4375)","0","pure_quanta_power","I9";
;
HDL_POWER"P0V9_CPU0_RT2_2A_2D"
CDS_LIB"pure_quanta_power";
"A"7;
END.
